# SCM (Grand Teton) — schematic netlist excerpt (pin names and nets, part order shuffled) for the footprints in the layout excerpt that follows; sources: Cadence DE-HDL packaged netlist, KiCad conversion of 12092022_DA0F0TMDCD0_F0T_Management_Board_D_brd_V3_OCP.brd

R884  Q_RES  33.2 1% CHIP  pkg 0402LF  page 14 : A = AC_PWR_BMC_BTN_R_N ; B = AC_PWR_BMC_BTN_N
R842  Q_RES  4.7K 1% CHIP  pkg 0402LF  page 27 : A = P3V3_AUX ; B = SMB_BMC_ALERT9_N

(kicad_pcb
	(version 20260206)
	(generator "pcbnew")
	(generator_version "10.0")
	(general
		(thickness 1.6)
		(legacy_teardrops no)
	)
	(paper "A4")
	(title_block
		(title "12092022_DA0F0TMDCD0_F0T_Management_Board_D_brd_V3_OCP.brd")
		(comment 1 "Grand Teton / footprints 864-865 of 1440")
	)
	(layers
		(0 "F.Cu" signal "TOP")
		(4 "In1.Cu" signal "GND")
		(6 "In2.Cu" signal "IN1")
		(8 "In3.Cu" signal "GND1")
		(10 "In4.Cu" signal "IN2")
		(12 "In5.Cu" signal "VCC")
		(14 "In6.Cu" signal "VCC1")
		(16 "In7.Cu" signal "IN3")
		(18 "In8.Cu" signal "GND2")
		(20 "In9.Cu" signal "IN4")
		(22 "In10.Cu" signal "GND3")
		(2 "B.Cu" signal "BOTTOM")
		(9 "F.Adhes" user "F.Adhesive")
		(11 "B.Adhes" user "B.Adhesive")
		(13 "F.Paste" user "Package Geometry/Pastemask Top")
		(15 "B.Paste" user "Package Geometry/Pastemask Bottom")
		(5 "F.SilkS" user "Ref Des/Silkscreen Top")
		(7 "B.SilkS" user "Ref Des/Silkscreen Bottom")
		(1 "F.Mask" user "Board Geometry/Soldermask Top")
		(3 "B.Mask" user "Board Geometry/Soldermask Bottom")
		(17 "Dwgs.User" user "User.Drawings")
		(19 "Cmts.User" user "User.Comments")
		(21 "Eco1.User" user "User.Eco1")
		(23 "Eco2.User" user "User.Eco2")
		(25 "Edge.Cuts" user "Board Geometry/Outline")
		(27 "Margin" user)
		(31 "F.CrtYd" user "Package Geometry/Place Bound Top")
		(29 "B.CrtYd" user "Package Geometry/Place Bound Bottom")
		(35 "F.Fab" user "Ref Des/Assembly Top")
		(33 "B.Fab" user "Ref Des/Assembly Bottom")
	)
	(footprint ""
		(layer "B.Cu")
		(at 66.802 -13.462 180)
		(property "Reference" "R884"
			(at 0 0 0)
			(layer "B.SilkS")
			(hide yes)
			(effects
				(font
					(size 1.27 1.27)
				)
				(justify mirror)
			)
		)
		(property "Value" ""
			(at 0 0 0)
			(layer "B.Fab")
			(effects
				(font
					(size 1.27 1.27)
				)
				(justify mirror)
			)
		)
		(duplicate_pad_numbers_are_jumpers no)
		(fp_line
			(start 0.7874 0.4064)
			(end 0.7874 -0.4064)
			(stroke
				(width 0.1524)
				(type default)
			)
			(layer "B.SilkS")
		)
		(fp_line
			(start 0.7874 -0.4064)
			(end -0.7874 -0.4064)
			(stroke
				(width 0.1524)
				(type default)
			)
			(layer "B.SilkS")
		)
		(fp_line
			(start -0.7874 0.4064)
			(end 0.7874 0.4064)
			(stroke
				(width 0.1524)
				(type default)
			)
			(layer "B.SilkS")
		)
		(fp_line
			(start -0.7874 -0.4064)
			(end -0.7874 0.4064)
			(stroke
				(width 0.1524)
				(type default)
			)
			(layer "B.SilkS")
		)
		(fp_line
			(start 0.67945 0.3048)
			(end 0.67945 -0.305054)
			(stroke
				(width 0.1)
				(type default)
			)
			(layer "B.Fab")
		)
		(fp_line
			(start 0.67945 -0.305054)
			(end 0.12065 -0.305054)
			(stroke
				(width 0.1)
				(type default)
			)
			(layer "B.Fab")
		)
		(fp_line
			(start 0.12065 0.3048)
			(end 0.67945 0.3048)
			(stroke
				(width 0.1)
				(type default)
			)
			(layer "B.Fab")
		)
		(fp_line
			(start 0.12065 0.2794)
			(end 0.12065 0.3048)
			(stroke
				(width 0.1)
				(type default)
			)
			(layer "B.Fab")
		)
		(fp_line
			(start 0.12065 -0.2794)
			(end -0.12065 -0.2794)
			(stroke
				(width 0.1)
				(type default)
			)
			(layer "B.Fab")
		)
		(fp_line
			(start 0.12065 -0.305054)
			(end 0.12065 -0.2794)
			(stroke
				(width 0.1)
				(type default)
			)
			(layer "B.Fab")
		)
		(fp_line
			(start -0.120396 0.3048)
			(end -0.120396 0.2794)
			(stroke
				(width 0.1)
				(type default)
			)
			(layer "B.Fab")
		)
		(fp_line
			(start -0.120396 0.2794)
			(end 0.12065 0.2794)
			(stroke
				(width 0.1)
				(type default)
			)
			(layer "B.Fab")
		)
		(fp_line
			(start -0.12065 -0.2794)
			(end -0.12065 -0.3048)
			(stroke
				(width 0.1)
				(type default)
			)
			(layer "B.Fab")
		)
		(fp_line
			(start -0.12065 -0.3048)
			(end -0.67945 -0.3048)
			(stroke
				(width 0.1)
				(type default)
			)
			(layer "B.Fab")
		)
		(fp_line
			(start -0.67945 0.3048)
			(end -0.120396 0.3048)
			(stroke
				(width 0.1)
				(type default)
			)
			(layer "B.Fab")
		)
		(fp_line
			(start -0.67945 -0.3048)
			(end -0.67945 0.3048)
			(stroke
				(width 0.1)
				(type default)
			)
			(layer "B.Fab")
		)
		(pad "1" smd circle
			(at 0.40005 0)
			(size 0 0)
			(layers "B.Cu" "B.Mask" "B.Paste")
			(net "AC_PWR_BMC_BTN_R_N")
		)
		(pad "2" smd circle
			(at -0.40005 0)
			(size 0 0)
			(layers "B.Cu" "B.Mask" "B.Paste")
			(net "AC_PWR_BMC_BTN_N")
		)
	)
	(footprint ""
		(layer "B.Cu")
		(at 47.92726 -67.818 180)
		(property "Reference" "R842"
			(at 0 0 0)
			(layer "B.SilkS")
			(hide yes)
			(effects
				(font
					(size 1.27 1.27)
				)
				(justify mirror)
			)
		)
		(property "Value" ""
			(at 0 0 0)
			(layer "B.Fab")
			(effects
				(font
					(size 1.27 1.27)
				)
				(justify mirror)
			)
		)
		(duplicate_pad_numbers_are_jumpers no)
		(fp_line
			(start 0.7874 0.4064)
			(end 0.7874 -0.4064)
			(stroke
				(width 0.1524)
				(type default)
			)
			(layer "B.SilkS")
		)
		(fp_line
			(start 0.7874 -0.4064)
			(end -0.7874 -0.4064)
			(stroke
				(width 0.1524)
				(type default)
			)
			(layer "B.SilkS")
		)
		(fp_line
			(start -0.7874 0.4064)
			(end 0.7874 0.4064)
			(stroke
				(width 0.1524)
				(type default)
			)
			(layer "B.SilkS")
		)
		(fp_line
			(start -0.7874 -0.4064)
			(end -0.7874 0.4064)
			(stroke
				(width 0.1524)
				(type default)
			)
			(layer "B.SilkS")
		)
		(fp_line
			(start 0.67945 0.3048)
			(end 0.67945 -0.305054)
			(stroke
				(width 0.1)
				(type default)
			)
			(layer "B.Fab")
		)
		(fp_line
			(start 0.67945 -0.305054)
			(end 0.12065 -0.305054)
			(stroke
				(width 0.1)
				(type default)
			)
			(layer "B.Fab")
		)
		(fp_line
			(start 0.12065 0.3048)
			(end 0.67945 0.3048)
			(stroke
				(width 0.1)
				(type default)
			)
			(layer "B.Fab")
		)
		(fp_line
			(start 0.12065 0.2794)
			(end 0.12065 0.3048)
			(stroke
				(width 0.1)
				(type default)
			)
			(layer "B.Fab")
		)
		(fp_line
			(start 0.12065 -0.2794)
			(end -0.12065 -0.2794)
			(stroke
				(width 0.1)
				(type default)
			)
			(layer "B.Fab")
		)
		(fp_line
			(start 0.12065 -0.305054)
			(end 0.12065 -0.2794)
			(stroke
				(width 0.1)
				(type default)
			)
			(layer "B.Fab")
		)
		(fp_line
			(start -0.120396 0.3048)
			(end -0.120396 0.2794)
			(stroke
				(width 0.1)
				(type default)
			)
			(layer "B.Fab")
		)
		(fp_line
			(start -0.120396 0.2794)
			(end 0.12065 0.2794)
			(stroke
				(width 0.1)
				(type default)
			)
			(layer "B.Fab")
		)
		(fp_line
			(start -0.12065 -0.2794)
			(end -0.12065 -0.3048)
			(stroke
				(width 0.1)
				(type default)
			)
			(layer "B.Fab")
		)
		(fp_line
			(start -0.12065 -0.3048)
			(end -0.67945 -0.3048)
			(stroke
				(width 0.1)
				(type default)
			)
			(layer "B.Fab")
		)
		(fp_line
			(start -0.67945 0.3048)
			(end -0.120396 0.3048)
			(stroke
				(width 0.1)
				(type default)
			)
			(layer "B.Fab")
		)
		(fp_line
			(start -0.67945 -0.3048)
			(end -0.67945 0.3048)
			(stroke
				(width 0.1)
				(type default)
			)
			(layer "B.Fab")
		)
		(pad "1" smd circle
			(at 0.40005 0)
			(size 0 0)
			(layers "B.Cu" "B.Mask" "B.Paste")
			(net "P3V3_AUX")
		)
		(pad "2" smd circle
			(at -0.40005 0)
			(size 0 0)
			(layers "B.Cu" "B.Mask" "B.Paste")
			(net "SMB_BMC_ALERT9_N")
		)
	)
)
